(kicad_pcb
	(version 20241229)
	(generator "pcbnew")
	(generator_version "9.0")
	(general
		(thickness 1.61)
		(legacy_teardrops no)
	)
	(paper "A3")
	(title_block
		(title "RDIMM DDR5 Tester")
		(date "2026-05-21")
		(rev "2.2.0")
		(company "Antmicro")
		(comment 9 "footprints 258-262 of 796")
	)
	(layers
		(0 "F.Cu" signal)
		(4 "In1.Cu" power)
		(6 "In2.Cu" mixed)
		(8 "In3.Cu" power)
		(10 "In4.Cu" mixed)
		(12 "In5.Cu" power)
		(14 "In6.Cu" mixed)
		(16 "In7.Cu" power)
		(18 "In8.Cu" power)
		(20 "In9.Cu" mixed)
		(22 "In10.Cu" power)
		(2 "B.Cu" signal)
		(9 "F.Adhes" user "F.Adhesive")
		(11 "B.Adhes" user "B.Adhesive")
		(13 "F.Paste" user)
		(15 "B.Paste" user)
		(5 "F.SilkS" user "F.Silkscreen")
		(7 "B.SilkS" user "B.Silkscreen")
		(1 "F.Mask" user)
		(3 "B.Mask" user)
		(17 "Dwgs.User" user "User.Drawings")
		(19 "Cmts.User" user "User.Comments")
		(21 "Eco1.User" user "User.Eco1")
		(23 "Eco2.User" user "User.Eco2")
		(25 "Edge.Cuts" user)
		(27 "Margin" user)
		(31 "F.CrtYd" user "F.Courtyard")
		(29 "B.CrtYd" user "B.Courtyard")
		(35 "F.Fab" user)
		(33 "B.Fab" user)
	)
	(footprint "antmicro-footprints:C_0402_1005Metric"
		(layer "F.Cu")
		(at 121.5 164 90)
		(descr "Capacitor SMD 0402")
		(tags "capacitor SMD 0402")
		(property "Reference" "C295"
			(at -2.03 -0.63 90)
			(layer "F.SilkS")
			(effects
				(font
					(size 0.7 0.7)
					(thickness 0.15)
				)
				(justify left bottom)
			)
		)
		(property "Value" "C_100n_0402"
			(at -1.022927 2.155213 90)
			(layer "F.Fab")
			(effects
				(font
					(size 0.7 0.7)
					(thickness 0.15)
				)
				(justify left bottom)
			)
		)
		(property "Datasheet" "https://www.murata.com/products/productdetail?partno=GRM155R61H104KE14%23"
			(at 0 0 90)
			(layer "F.Fab")
			(hide yes)
			(effects
				(font
					(size 1.27 1.27)
					(thickness 0.15)
				)
			)
		)
		(property "MPN" "GRM155R61H104KE14D"
			(at 0 0 90)
			(unlocked yes)
			(layer "F.Fab")
			(hide yes)
			(effects
				(font
					(size 1 1)
					(thickness 0.15)
				)
			)
		)
		(property "Manufacturer" "Murata"
			(at 0 0 90)
			(unlocked yes)
			(layer "F.Fab")
			(hide yes)
			(effects
				(font
					(size 1 1)
					(thickness 0.15)
				)
			)
		)
		(property "License" "Apache-2.0"
			(at 0 0 90)
			(unlocked yes)
			(layer "F.Fab")
			(hide yes)
			(effects
				(font
					(size 1 1)
					(thickness 0.15)
				)
			)
		)
		(property "Author" "Antmicro"
			(at 0 0 90)
			(unlocked yes)
			(layer "F.Fab")
			(hide yes)
			(effects
				(font
					(size 1 1)
					(thickness 0.15)
				)
			)
		)
		(property "Val" "100n"
			(at 0 0 90)
			(unlocked yes)
			(layer "F.Fab")
			(hide yes)
			(effects
				(font
					(size 1 1)
					(thickness 0.15)
				)
			)
		)
		(property "Voltage" "50V"
			(at 0 0 90)
			(unlocked yes)
			(layer "F.Fab")
			(hide yes)
			(effects
				(font
					(size 1 1)
					(thickness 0.15)
				)
			)
		)
		(property "Dielectric" "X5R"
			(at 0 0 90)
			(unlocked yes)
			(layer "F.Fab")
			(hide yes)
			(effects
				(font
					(size 1 1)
					(thickness 0.15)
				)
			)
		)
		(sheetname "/HDMI + SD Card/")
		(sheetfile "hdmi-sd-card.kicad_sch")
		(attr smd)
		(fp_rect
			(start -0.925 -0.47)
			(end 0.925 0.47)
			(stroke
				(width 0.05)
				(type default)
			)
			(fill no)
			(layer "F.CrtYd")
		)
		(fp_line
			(start 0.504 -0.25)
			(end 0.504 0.248)
			(stroke
				(width 0.15)
				(type solid)
			)
			(layer "F.Fab")
		)
		(fp_line
			(start -0.494 -0.25)
			(end 0.504 -0.25)
			(stroke
				(width 0.15)
				(type solid)
			)
			(layer "F.Fab")
		)
		(fp_line
			(start 0.504 0.248)
			(end -0.494 0.248)
			(stroke
				(width 0.15)
				(type solid)
			)
			(layer "F.Fab")
		)
		(fp_line
			(start -0.494 0.248)
			(end -0.494 -0.25)
			(stroke
				(width 0.15)
				(type solid)
			)
			(layer "F.Fab")
		)
		(fp_text user "Author: Antmicro"
			(at -0.939 3.399 90)
			(layer "F.Fab")
			(effects
				(font
					(size 0.7 0.7)
					(thickness 0.15)
				)
				(justify left bottom)
			)
		)
		(fp_text user "License: Apache-2.0"
			(at -0.939 5.799 90)
			(layer "F.Fab")
			(effects
				(font
					(size 0.7 0.7)
					(thickness 0.15)
				)
				(justify left bottom)
			)
		)
		(fp_text user "${REFERENCE}"
			(at -0.939 4.599 90)
			(layer "F.Fab")
			(effects
				(font
					(size 0.7 0.7)
					(thickness 0.15)
				)
				(justify left bottom)
			)
		)
		(pad "1" smd roundrect
			(at -0.48 0 90)
			(size 0.59 0.64)
			(layers "F.Cu" "F.Mask" "F.Paste")
			(roundrect_rratio 0.25)
			(net 1 "GND")
			(pintype "passive")
		)
		(pad "2" smd roundrect
			(at 0.48 0 90)
			(size 0.59 0.64)
			(layers "F.Cu" "F.Mask" "F.Paste")
			(roundrect_rratio 0.25)
			(net 647 "/HDMI + SD Card/VCCB")
			(pintype "passive")
		)
	)
	(footprint "antmicro-footprints:R_0402_1005Metric"
		(layer "F.Cu")
		(at 122.681 166.1125 90)
		(descr "Resistor SMD 0402")
		(tags "resistor SMD 0402")
		(property "Reference" "R230"
			(at 0.9125 3.969 90)
			(layer "F.SilkS")
			(effects
				(font
					(size 0.7 0.7)
					(thickness 0.15)
				)
				(justify left bottom)
			)
		)
		(property "Value" "R_64k9_0402"
			(at -1.011843 1.772047 90)
			(layer "F.Fab")
			(effects
				(font
					(size 0.7 0.7)
					(thickness 0.15)
				)
				(justify left bottom)
			)
		)
		(property "Datasheet" "https://www.bourns.com/docs/product-datasheets/cr.pdf"
			(at 0 0 90)
			(layer "F.Fab")
			(hide yes)
			(effects
				(font
					(size 1.27 1.27)
					(thickness 0.15)
				)
			)
		)
		(property "MPN" "CR0402-FX-6492GLF"
			(at 0 0 90)
			(unlocked yes)
			(layer "F.Fab")
			(hide yes)
			(effects
				(font
					(size 1 1)
					(thickness 0.15)
				)
			)
		)
		(property "Manufacturer" "Bourns"
			(at 0 0 90)
			(unlocked yes)
			(layer "F.Fab")
			(hide yes)
			(effects
				(font
					(size 1 1)
					(thickness 0.15)
				)
			)
		)
		(property "License" "Apache-2.0"
			(at 0 0 90)
			(unlocked yes)
			(layer "F.Fab")
			(hide yes)
			(effects
				(font
					(size 1 1)
					(thickness 0.15)
				)
			)
		)
		(property "Author" "Antmicro"
			(at 0 0 90)
			(unlocked yes)
			(layer "F.Fab")
			(hide yes)
			(effects
				(font
					(size 1 1)
					(thickness 0.15)
				)
			)
		)
		(property "Val" "64k9"
			(at 0 0 90)
			(unlocked yes)
			(layer "F.Fab")
			(hide yes)
			(effects
				(font
					(size 1 1)
					(thickness 0.15)
				)
			)
		)
		(property "Tolerance" "1%"
			(at 0 0 90)
			(unlocked yes)
			(layer "F.Fab")
			(hide yes)
			(effects
				(font
					(size 1 1)
					(thickness 0.15)
				)
			)
		)
		(sheetname "/HDMI + SD Card/")
		(sheetfile "hdmi-sd-card.kicad_sch")
		(attr smd exclude_from_bom dnp)
		(fp_rect
			(start -0.925 -0.47)
			(end 0.925 0.47)
			(stroke
				(width 0.05)
				(type default)
			)
			(fill no)
			(layer "F.CrtYd")
		)
		(fp_rect
			(start -0.5 -0.25)
			(end 0.5 0.25)
			(stroke
				(width 0.15)
				(type solid)
			)
			(fill no)
			(layer "F.Fab")
		)
		(fp_text user "Author: Antmicro"
			(at -0.95 4.169 90)
			(layer "F.Fab")
			(effects
				(font
					(size 0.7 0.7)
					(thickness 0.15)
				)
				(justify left bottom)
			)
		)
		(fp_text user "${REFERENCE}"
			(at -0.95 3.168 90)
			(layer "F.Fab")
			(effects
				(font
					(size 0.7 0.7)
					(thickness 0.15)
				)
				(justify left bottom)
			)
		)
		(fp_text user "License: Apache-2.0"
			(at -0.95 5.169 90)
			(layer "F.Fab")
			(effects
				(font
					(size 0.7 0.7)
					(thickness 0.15)
				)
				(justify left bottom)
			)
		)
		(pad "1" smd roundrect
			(at -0.48 0 90)
			(size 0.59 0.64)
			(layers "F.Cu" "F.Mask" "F.Paste")
			(roundrect_rratio 0.25)
			(net 740 "/HDMI + SD Card/SLEW_CTL")
			(pintype "passive")
		)
		(pad "2" smd roundrect
			(at 0.48 0 90)
			(size 0.59 0.64)
			(layers "F.Cu" "F.Mask" "F.Paste")
			(roundrect_rratio 0.25)
			(net 151 "+3V3")
			(pintype "passive")
		)
	)
	(footprint "antmicro-footprints:C_0402_1005Metric"
		(layer "F.Cu")
		(at 226.365 179.185001 180)
		(descr "Capacitor SMD 0402")
		(tags "capacitor SMD 0402")
		(property "Reference" "C218"
			(at 1.335 -0.404999 315)
			(layer "F.SilkS")
			(effects
				(font
					(size 0.7 0.7)
					(thickness 0.15)
				)
				(justify right bottom)
			)
		)
		(property "Value" "C_4u7_25V_0402"
			(at -1.022927 2.155213 0)
			(layer "F.Fab")
			(effects
				(font
					(size 0.7 0.7)
					(thickness 0.15)
				)
				(justify right bottom)
			)
		)
		(property "Datasheet" "https://www.murata.com/products/productdetail?partno=GRM155C61E475ME15%23"
			(at 0 0 180)
			(layer "F.Fab")
			(hide yes)
			(effects
				(font
					(size 1.27 1.27)
					(thickness 0.15)
				)
			)
		)
		(property "MPN" "GRM155C61E475ME15J"
			(at 0 0 180)
			(unlocked yes)
			(layer "F.Fab")
			(hide yes)
			(effects
				(font
					(size 1 1)
					(thickness 0.15)
				)
			)
		)
		(property "Manufacturer" "Murata"
			(at 0 0 180)
			(unlocked yes)
			(layer "F.Fab")
			(hide yes)
			(effects
				(font
					(size 1 1)
					(thickness 0.15)
				)
			)
		)
		(property "License" "Apache-2.0"
			(at 0 0 180)
			(unlocked yes)
			(layer "F.Fab")
			(hide yes)
			(effects
				(font
					(size 1 1)
					(thickness 0.15)
				)
			)
		)
		(property "Author" "Antmicro"
			(at 0 0 180)
			(unlocked yes)
			(layer "F.Fab")
			(hide yes)
			(effects
				(font
					(size 1 1)
					(thickness 0.15)
				)
			)
		)
		(property "Val" "4u7"
			(at 0 0 180)
			(unlocked yes)
			(layer "F.Fab")
			(hide yes)
			(effects
				(font
					(size 1 1)
					(thickness 0.15)
				)
			)
		)
		(property "Voltage" "25V"
			(at 0 0 180)
			(unlocked yes)
			(layer "F.Fab")
			(hide yes)
			(effects
				(font
					(size 1 1)
					(thickness 0.15)
				)
			)
		)
		(property "Dielectric" "X5S"
			(at 0 0 180)
			(unlocked yes)
			(layer "F.Fab")
			(hide yes)
			(effects
				(font
					(size 1 1)
					(thickness 0.15)
				)
			)
		)
		(sheetname "/Supply/DC-DC VCCINT/")
		(sheetfile "dc-dc-vccint.kicad_sch")
		(attr smd)
		(fp_rect
			(start -0.925 -0.47)
			(end 0.925 0.47)
			(stroke
				(width 0.05)
				(type default)
			)
			(fill no)
			(layer "F.CrtYd")
		)
		(fp_line
			(start 0.504 0.248)
			(end -0.494 0.248)
			(stroke
				(width 0.15)
				(type solid)
			)
			(layer "F.Fab")
		)
		(fp_line
			(start 0.504 -0.25)
			(end 0.504 0.248)
			(stroke
				(width 0.15)
				(type solid)
			)
			(layer "F.Fab")
		)
		(fp_line
			(start -0.494 0.248)
			(end -0.494 -0.25)
			(stroke
				(width 0.15)
				(type solid)
			)
			(layer "F.Fab")
		)
		(fp_line
			(start -0.494 -0.25)
			(end 0.504 -0.25)
			(stroke
				(width 0.15)
				(type solid)
			)
			(layer "F.Fab")
		)
		(fp_text user "License: Apache-2.0"
			(at -0.939 5.799 180)
			(layer "F.Fab")
			(effects
				(font
					(size 0.7 0.7)
					(thickness 0.15)
				)
				(justify left bottom)
			)
		)
		(fp_text user "${REFERENCE}"
			(at -0.939 4.599 180)
			(layer "F.Fab")
			(effects
				(font
					(size 0.7 0.7)
					(thickness 0.15)
				)
				(justify left bottom)
			)
		)
		(fp_text user "Author: Antmicro"
			(at -0.939 3.399 180)
			(layer "F.Fab")
			(effects
				(font
					(size 0.7 0.7)
					(thickness 0.15)
				)
				(justify left bottom)
			)
		)
		(pad "1" smd roundrect
			(at -0.48 0 180)
			(size 0.59 0.64)
			(layers "F.Cu" "F.Mask" "F.Paste")
			(roundrect_rratio 0.25)
			(net 1 "GND")
			(pintype "passive")
		)
		(pad "2" smd roundrect
			(at 0.48 0 180)
			(size 0.59 0.64)
			(layers "F.Cu" "F.Mask" "F.Paste")
			(roundrect_rratio 0.25)
			(net 49 "Net-(U36-V_{DRV})")
			(pintype "passive")
		)
	)
	(footprint "antmicro-footprints:C_Pol_EIA-D"
		(layer "F.Cu")
		(at 216.44 160.4 90)
		(property "Reference" "C12"
			(at -6 2.434998 90)
			(layer "F.SilkS")
			(effects
				(font
					(size 0.7 0.7)
					(thickness 0.15)
				)
				(justify left bottom)
			)
		)
		(property "Value" "C_Pol_1m_2.5V_KEMET-T520-D"
			(at 0 3.4 90)
			(layer "F.Fab")
			(effects
				(font
					(size 0.7 0.7)
					(thickness 0.15)
				)
				(justify left bottom)
			)
		)
		(property "Datasheet" "https://www.kemet.com/en/us/capacitors/product/T520D108M2R5ATE030.html"
			(at 0 0 90)
			(layer "F.Fab")
			(hide yes)
			(effects
				(font
					(size 1.27 1.27)
					(thickness 0.15)
				)
			)
		)
		(property "MPN" "T520D108M2R5ATE030"
			(at 0 0 90)
			(unlocked yes)
			(layer "F.Fab")
			(hide yes)
			(effects
				(font
					(size 1 1)
					(thickness 0.15)
				)
			)
		)
		(property "Manufacturer" "KEMET"
			(at 0 0 90)
			(unlocked yes)
			(layer "F.Fab")
			(hide yes)
			(effects
				(font
					(size 1 1)
					(thickness 0.15)
				)
			)
		)
		(property "License" "Apache-2.0"
			(at 0 0 90)
			(unlocked yes)
			(layer "F.Fab")
			(hide yes)
			(effects
				(font
					(size 1 1)
					(thickness 0.15)
				)
			)
		)
		(property "Author" "Antmicro"
			(at 0 0 90)
			(unlocked yes)
			(layer "F.Fab")
			(hide yes)
			(effects
				(font
					(size 1 1)
					(thickness 0.15)
				)
			)
		)
		(property "Val" "1000u"
			(at 0 0 90)
			(unlocked yes)
			(layer "F.Fab")
			(hide yes)
			(effects
				(font
					(size 1 1)
					(thickness 0.15)
				)
			)
		)
		(property "Voltage" "2.5V"
			(at 0 0 90)
			(unlocked yes)
			(layer "F.Fab")
			(hide yes)
			(effects
				(font
					(size 1 1)
					(thickness 0.15)
				)
			)
		)
		(property "Dielectric" "template_dielectric"
			(at 0 0 90)
			(unlocked yes)
			(layer "F.Fab")
			(hide yes)
			(effects
				(font
					(size 1 1)
					(thickness 0.15)
				)
			)
		)
		(sheetname "/FPGA power/")
		(sheetfile "fpga-power.kicad_sch")
		(attr smd)
		(fp_line
			(start 3.6 -2.2)
			(end 3.6 -1.6)
			(stroke
				(width 0.15)
				(type solid)
			)
			(layer "F.SilkS")
		)
		(fp_line
			(start -3.58 -2.2)
			(end 3.6 -2.2)
			(stroke
				(width 0.15)
				(type solid)
			)
			(layer "F.SilkS")
		)
		(fp_line
			(start -4.1 -2.025)
			(end -4.1 -1.625)
			(stroke
				(width 0.12)
				(type solid)
			)
			(layer "F.SilkS")
		)
		(fp_line
			(start -4.3 -1.825)
			(end -3.9 -1.825)
			(stroke
				(width 0.12)
				(type solid)
			)
			(layer "F.SilkS")
		)
		(fp_line
			(start -3.58 -1.6)
			(end -3.58 -2.2)
			(stroke
				(width 0.15)
				(type solid)
			)
			(layer "F.SilkS")
		)
		(fp_line
			(start 3.6 1.6)
			(end 3.6 2.2)
			(stroke
				(width 0.15)
				(type solid)
			)
			(layer "F.SilkS")
		)
		(fp_line
			(start 3.6 2.2)
			(end -3.58 2.2)
			(stroke
				(width 0.15)
				(type solid)
			)
			(layer "F.SilkS")
		)
		(fp_line
			(start -3.58 2.2)
			(end -3.58 1.6)
			(stroke
				(width 0.15)
				(type solid)
			)
			(layer "F.SilkS")
		)
		(fp_line
			(start 3.77 -2.4)
			(end 3.77 -1.51)
			(stroke
				(width 0.05)
				(type solid)
			)
			(layer "F.CrtYd")
		)
		(fp_line
			(start -3.775 -2.4)
			(end 3.77 -2.4)
			(stroke
				(width 0.05)
				(type solid)
			)
			(layer "F.CrtYd")
		)
		(fp_line
			(start -3.775 -2.4)
			(end -3.775 -1.5)
			(stroke
				(width 0.05)
				(type solid)
			)
			(layer "F.CrtYd")
		)
		(fp_line
			(start 4.505 -1.51)
			(end 4.505 1.5)
			(stroke
				(width 0.05)
				(type solid)
			)
			(layer "F.CrtYd")
		)
		(fp_line
			(start 3.77 -1.51)
			(end 4.505 -1.51)
			(stroke
				(width 0.05)
				(type solid)
			)
			(layer "F.CrtYd")
		)
		(fp_line
			(start -3.775 -1.5)
			(end -4.505 -1.5)
			(stroke
				(width 0.05)
				(type solid)
			)
			(layer "F.CrtYd")
		)
		(fp_line
			(start 4.505 1.51)
			(end 3.77 1.51)
			(stroke
				(width 0.05)
				(type solid)
			)
			(layer "F.CrtYd")
		)
		(fp_line
			(start 3.77 1.51)
			(end 3.77 2.4)
			(stroke
				(width 0.05)
				(type solid)
			)
			(layer "F.CrtYd")
		)
		(fp_line
			(start -3.77 1.51)
			(end -4.505 1.51)
			(stroke
				(width 0.05)
				(type solid)
			)
			(layer "F.CrtYd")
		)
		(fp_line
			(start -4.505 1.51)
			(end -4.505 -1.5)
			(stroke
				(width 0.05)
				(type solid)
			)
			(layer "F.CrtYd")
		)
		(fp_line
			(start 3.77 2.4)
			(end -3.77 2.4)
			(stroke
				(width 0.05)
				(type solid)
			)
			(layer "F.CrtYd")
		)
		(fp_line
			(start -3.77 2.4)
			(end -3.77 1.51)
			(stroke
				(width 0.05)
				(type solid)
			)
			(layer "F.CrtYd")
		)
		(fp_rect
			(start -3.65 -2.15)
			(end 3.65 2.15)
			(stroke
				(width 0.15)
				(type solid)
			)
			(fill no)
			(layer "F.Fab")
		)
		(fp_text user "Author: Antmicro"
			(at -4.5 7.6 90)
			(layer "F.Fab")
			(effects
				(font
					(size 0.7 0.7)
					(thickness 0.15)
				)
				(justify left bottom)
			)
		)
		(fp_text user "License: Apache-2.0"
			(at -4.5 6.6 90)
			(layer "F.Fab")
			(effects
				(font
					(size 0.7 0.7)
					(thickness 0.15)
				)
				(justify left bottom)
			)
		)
		(fp_text user "${REFERENCE}"
			(at -4.5 5.6 90)
			(layer "F.Fab")
			(effects
				(font
					(size 0.7 0.7)
					(thickness 0.15)
				)
				(justify left bottom)
			)
		)
		(pad "1" smd roundrect
			(at -3.1 0 90)
			(size 2.31 2.52)
			(layers "F.Cu" "F.Mask" "F.Paste")
			(roundrect_rratio 0.1)
			(net 553 "+0V85")
			(pintype "passive")
		)
		(pad "2" smd roundrect
			(at 3.1 0 90)
			(size 2.31 2.52)
			(layers "F.Cu" "F.Mask" "F.Paste")
			(roundrect_rratio 0.1)
			(net 1 "GND")
			(pintype "passive")
		)
	)
	(footprint "antmicro-footprints:R_0402_1005Metric"
		(layer "F.Cu")
		(at 117.52 139.083 -90)
		(descr "Resistor SMD 0402")
		(tags "resistor SMD 0402")
		(property "Reference" "R183"
			(at -3.792 0.48 90)
			(layer "F.SilkS")
			(effects
				(font
					(size 0.7 0.7)
					(thickness 0.15)
				)
				(justify right top)
			)
		)
		(property "Value" "R_330R_0402"
			(at -1.011843 1.772047 90)
			(layer "F.Fab")
			(effects
				(font
					(size 0.7 0.7)
					(thickness 0.15)
				)
				(justify right top)
			)
		)
		(property "Datasheet" "https://www.bourns.com/docs/product-datasheets/cr.pdf"
			(at 0 0 90)
			(layer "F.Fab")
			(hide yes)
			(effects
				(font
					(size 1.27 1.27)
					(thickness 0.15)
				)
			)
		)
		(property "Manufacturer" "Bourns"
			(at 0 0 270)
			(unlocked yes)
			(layer "F.Fab")
			(hide yes)
			(effects
				(font
					(size 1 1)
					(thickness 0.15)
				)
			)
		)
		(property "MPN" "CR0402-FX-3300GLF"
			(at 0 0 270)
			(unlocked yes)
			(layer "F.Fab")
			(hide yes)
			(effects
				(font
					(size 1 1)
					(thickness 0.15)
				)
			)
		)
		(property "Val" "330R"
			(at 0 0 270)
			(unlocked yes)
			(layer "F.Fab")
			(hide yes)
			(effects
				(font
					(size 1 1)
					(thickness 0.15)
				)
			)
		)
		(property "License" "Apache-2.0"
			(at 0 0 270)
			(unlocked yes)
			(layer "F.Fab")
			(hide yes)
			(effects
				(font
					(size 1 1)
					(thickness 0.15)
				)
			)
		)
		(property "Author" "Antmicro"
			(at 0 0 270)
			(unlocked yes)
			(layer "F.Fab")
			(hide yes)
			(effects
				(font
					(size 1 1)
					(thickness 0.15)
				)
			)
		)
		(property "Tolerance" "1%"
			(at 0 0 270)
			(unlocked yes)
			(layer "F.Fab")
			(hide yes)
			(effects
				(font
					(size 1 1)
					(thickness 0.15)
				)
			)
		)
		(sheetname "/Debug FTDI + VNA/")
		(sheetfile "debug-ftdi.kicad_sch")
		(attr smd)
		(fp_rect
			(start -0.925 -0.47)
			(end 0.925 0.47)
			(stroke
				(width 0.05)
				(type default)
			)
			(fill no)
			(layer "F.CrtYd")
		)
		(fp_rect
			(start -0.5 -0.25)
			(end 0.5 0.25)
			(stroke
				(width 0.15)
				(type solid)
			)
			(fill no)
			(layer "F.Fab")
		)
		(fp_text user "License: Apache-2.0"
			(at -0.95 5.169 270)
			(layer "F.Fab")
			(effects
				(font
					(size 0.7 0.7)
					(thickness 0.15)
				)
				(justify left bottom)
			)
		)
		(fp_text user "${REFERENCE}"
			(at -0.95 3.168 270)
			(layer "F.Fab")
			(effects
				(font
					(size 0.7 0.7)
					(thickness 0.15)
				)
				(justify left bottom)
			)
		)
		(fp_text user "Author: Antmicro"
			(at -0.95 4.169 270)
			(layer "F.Fab")
			(effects
				(font
					(size 0.7 0.7)
					(thickness 0.15)
				)
				(justify left bottom)
			)
		)
		(pad "1" smd roundrect
			(at -0.48 0 270)
			(size 0.59 0.64)
			(layers "F.Cu" "F.Mask" "F.Paste")
			(roundrect_rratio 0.25)
			(net 220 "Net-(D17-C)")
			(pintype "passive")
		)
		(pad "2" smd roundrect
			(at 0.48 0 270)
			(size 0.59 0.64)
			(layers "F.Cu" "F.Mask" "F.Paste")
			(roundrect_rratio 0.25)
			(net 1 "GND")
			(pintype "passive")
		)
	)
)
